# T6G (Grand Teton) — schematic netlist excerpt (pin names and nets, part order shuffled) for the footprints in the layout excerpt that follows; sources: Cadence DE-HDL packaged netlist, KiCad conversion of 04192023_DAF0TMB3IC0_F0TG_MB_C_brd_V02_OCP.brd

R1546  Q_RES  1K 1% CHIP  pkg 0402LF  page 151 : A = P3V3_AUX ; B = RST_MB_STBY_N
R291  Q_RES  1K 1% CHIP  pkg 0402LF  page 86 : A = PWRGD_CHA_CPU0_DIMM0 ; B = PWRGD_CHAF_CPU0

(kicad_pcb
	(version 20260206)
	(generator "pcbnew")
	(generator_version "10.0")
	(general
		(thickness 1.6)
		(legacy_teardrops no)
	)
	(paper "A4")
	(title_block
		(title "04192023_DAF0TMB3IC0_F0TG_MB_C_brd_V02_OCP.brd")
		(comment 1 "Grand Teton / footprints 7111-7112 of 8354")
	)
	(layers
		(0 "F.Cu" signal "TOP")
		(4 "In1.Cu" signal "GND")
		(6 "In2.Cu" signal "IN1")
		(8 "In3.Cu" signal "GND1")
		(10 "In4.Cu" signal "IN2")
		(12 "In5.Cu" signal "GND2")
		(14 "In6.Cu" signal "IN3")
		(16 "In7.Cu" signal "GND3")
		(18 "In8.Cu" signal "VCC")
		(20 "In9.Cu" signal "VCC1")
		(22 "In10.Cu" signal "GND4")
		(24 "In11.Cu" signal "IN4")
		(26 "In12.Cu" signal "GND5")
		(28 "In13.Cu" signal "IN5")
		(30 "In14.Cu" signal "GND6")
		(32 "In15.Cu" signal "IN6")
		(34 "In16.Cu" signal "GND7")
		(2 "B.Cu" signal "BOTTOM")
		(9 "F.Adhes" user "F.Adhesive")
		(11 "B.Adhes" user "B.Adhesive")
		(13 "F.Paste" user "Package Geometry/Pastemask Top")
		(15 "B.Paste" user "Package Geometry/Pastemask Bottom")
		(5 "F.SilkS" user "Ref Des/Silkscreen Top")
		(7 "B.SilkS" user "Ref Des/Silkscreen Bottom")
		(1 "F.Mask" user "Board Geometry/Soldermask Top")
		(3 "B.Mask" user "Board Geometry/Soldermask Bottom")
		(17 "Dwgs.User" user "User.Drawings")
		(19 "Cmts.User" user "User.Comments")
		(21 "Eco1.User" user "User.Eco1")
		(23 "Eco2.User" user "User.Eco2")
		(25 "Edge.Cuts" user "Board Geometry/Outline")
		(27 "Margin" user)
		(31 "F.CrtYd" user "Package Geometry/Place Bound Top")
		(29 "B.CrtYd" user "Package Geometry/Place Bound Bottom")
		(35 "F.Fab" user "Ref Des/Assembly Top")
		(33 "B.Fab" user "Ref Des/Assembly Bottom")
	)
	(footprint ""
		(layer "B.Cu")
		(at 300.304454 -190.82131)
		(property "Reference" "R291"
			(at 0 0 0)
			(layer "B.SilkS")
			(hide yes)
			(effects
				(font
					(size 1.27 1.27)
				)
				(justify mirror)
			)
		)
		(property "Value" ""
			(at 0 0 0)
			(layer "B.Fab")
			(effects
				(font
					(size 1.27 1.27)
				)
				(justify mirror)
			)
		)
		(duplicate_pad_numbers_are_jumpers no)
		(fp_line
			(start -0.7874 -0.4064)
			(end -0.7874 0.4064)
			(stroke
				(width 0.1524)
				(type default)
			)
			(layer "B.SilkS")
		)
		(fp_line
			(start -0.7874 0.4064)
			(end 0.7874 0.4064)
			(stroke
				(width 0.1524)
				(type default)
			)
			(layer "B.SilkS")
		)
		(fp_line
			(start 0.7874 -0.4064)
			(end -0.7874 -0.4064)
			(stroke
				(width 0.1524)
				(type default)
			)
			(layer "B.SilkS")
		)
		(fp_line
			(start 0.7874 0.4064)
			(end 0.7874 -0.4064)
			(stroke
				(width 0.1524)
				(type default)
			)
			(layer "B.SilkS")
		)
		(fp_line
			(start -0.67945 -0.3048)
			(end -0.67945 0.3048)
			(stroke
				(width 0.1)
				(type default)
			)
			(layer "B.Fab")
		)
		(fp_line
			(start -0.67945 0.3048)
			(end -0.120396 0.3048)
			(stroke
				(width 0.1)
				(type default)
			)
			(layer "B.Fab")
		)
		(fp_line
			(start -0.12065 -0.3048)
			(end -0.67945 -0.3048)
			(stroke
				(width 0.1)
				(type default)
			)
			(layer "B.Fab")
		)
		(fp_line
			(start -0.12065 -0.2794)
			(end -0.12065 -0.3048)
			(stroke
				(width 0.1)
				(type default)
			)
			(layer "B.Fab")
		)
		(fp_line
			(start -0.120396 0.2794)
			(end 0.12065 0.2794)
			(stroke
				(width 0.1)
				(type default)
			)
			(layer "B.Fab")
		)
		(fp_line
			(start -0.120396 0.3048)
			(end -0.120396 0.2794)
			(stroke
				(width 0.1)
				(type default)
			)
			(layer "B.Fab")
		)
		(fp_line
			(start 0.12065 -0.305054)
			(end 0.12065 -0.2794)
			(stroke
				(width 0.1)
				(type default)
			)
			(layer "B.Fab")
		)
		(fp_line
			(start 0.12065 -0.2794)
			(end -0.12065 -0.2794)
			(stroke
				(width 0.1)
				(type default)
			)
			(layer "B.Fab")
		)
		(fp_line
			(start 0.12065 0.2794)
			(end 0.12065 0.3048)
			(stroke
				(width 0.1)
				(type default)
			)
			(layer "B.Fab")
		)
		(fp_line
			(start 0.12065 0.3048)
			(end 0.67945 0.3048)
			(stroke
				(width 0.1)
				(type default)
			)
			(layer "B.Fab")
		)
		(fp_line
			(start 0.67945 -0.305054)
			(end 0.12065 -0.305054)
			(stroke
				(width 0.1)
				(type default)
			)
			(layer "B.Fab")
		)
		(fp_line
			(start 0.67945 0.3048)
			(end 0.67945 -0.305054)
			(stroke
				(width 0.1)
				(type default)
			)
			(layer "B.Fab")
		)
		(pad "1" smd circle
			(at 0.40005 0 180)
			(size 0 0)
			(layers "B.Cu" "B.Mask" "B.Paste")
			(net "PWRGD_CHA_CPU0_DIMM0")
		)
		(pad "2" smd circle
			(at -0.40005 0 180)
			(size 0 0)
			(layers "B.Cu" "B.Mask" "B.Paste")
			(net "PWRGD_CHAF_CPU0")
		)
	)
	(footprint ""
		(layer "B.Cu")
		(at 144.102582 -17.313148 90)
		(property "Reference" "R1546"
			(at 0 0 90)
			(layer "B.SilkS")
			(hide yes)
			(effects
				(font
					(size 1.27 1.27)
				)
				(justify mirror)
			)
		)
		(property "Value" ""
			(at 0 0 90)
			(layer "B.Fab")
			(effects
				(font
					(size 1.27 1.27)
				)
				(justify mirror)
			)
		)
		(duplicate_pad_numbers_are_jumpers no)
		(fp_line
			(start 0.7874 -0.4064)
			(end -0.7874 -0.4064)
			(stroke
				(width 0.1524)
				(type default)
			)
			(layer "B.SilkS")
		)
		(fp_line
			(start -0.7874 -0.4064)
			(end -0.7874 0.4064)
			(stroke
				(width 0.1524)
				(type default)
			)
			(layer "B.SilkS")
		)
		(fp_line
			(start 0.7874 0.4064)
			(end 0.7874 -0.4064)
			(stroke
				(width 0.1524)
				(type default)
			)
			(layer "B.SilkS")
		)
		(fp_line
			(start -0.7874 0.4064)
			(end 0.7874 0.4064)
			(stroke
				(width 0.1524)
				(type default)
			)
			(layer "B.SilkS")
		)
		(fp_line
			(start 0.67945 -0.305054)
			(end 0.12065 -0.305054)
			(stroke
				(width 0.1)
				(type default)
			)
			(layer "B.Fab")
		)
		(fp_line
			(start 0.12065 -0.305054)
			(end 0.12065 -0.2794)
			(stroke
				(width 0.1)
				(type default)
			)
			(layer "B.Fab")
		)
		(fp_line
			(start -0.12065 -0.3048)
			(end -0.67945 -0.3048)
			(stroke
				(width 0.1)
				(type default)
			)
			(layer "B.Fab")
		)
		(fp_line
			(start -0.67945 -0.3048)
			(end -0.67945 0.3048)
			(stroke
				(width 0.1)
				(type default)
			)
			(layer "B.Fab")
		)
		(fp_line
			(start 0.12065 -0.2794)
			(end -0.12065 -0.2794)
			(stroke
				(width 0.1)
				(type default)
			)
			(layer "B.Fab")
		)
		(fp_line
			(start -0.12065 -0.2794)
			(end -0.12065 -0.3048)
			(stroke
				(width 0.1)
				(type default)
			)
			(layer "B.Fab")
		)
		(fp_line
			(start 0.12065 0.2794)
			(end 0.12065 0.3048)
			(stroke
				(width 0.1)
				(type default)
			)
			(layer "B.Fab")
		)
		(fp_line
			(start -0.120396 0.2794)
			(end 0.12065 0.2794)
			(stroke
				(width 0.1)
				(type default)
			)
			(layer "B.Fab")
		)
		(fp_line
			(start 0.67945 0.3048)
			(end 0.67945 -0.305054)
			(stroke
				(width 0.1)
				(type default)
			)
			(layer "B.Fab")
		)
		(fp_line
			(start 0.12065 0.3048)
			(end 0.67945 0.3048)
			(stroke
				(width 0.1)
				(type default)
			)
			(layer "B.Fab")
		)
		(fp_line
			(start -0.120396 0.3048)
			(end -0.120396 0.2794)
			(stroke
				(width 0.1)
				(type default)
			)
			(layer "B.Fab")
		)
		(fp_line
			(start -0.67945 0.3048)
			(end -0.120396 0.3048)
			(stroke
				(width 0.1)
				(type default)
			)
			(layer "B.Fab")
		)
		(pad "1" smd circle
			(at 0.40005 0 270)
			(size 0 0)
			(layers "B.Cu" "B.Mask" "B.Paste")
			(net "P3V3_AUX")
		)
		(pad "2" smd circle
			(at -0.40005 0 270)
			(size 0 0)
			(layers "B.Cu" "B.Mask" "B.Paste")
			(net "RST_MB_STBY_N")
		)
	)
)
